(kicad_pcb
	(version 20260206)
	(generator "pcbnew")
	(generator_version "10.0")
	(general
		(thickness 1.6)
		(legacy_teardrops no)
	)
	(paper "A4")
	(title_block
		(title "12092022_DA0F0TYB4D0_F0T_Panel_BD_Front_D_brd_v02_OCP.brd")
		(comment 1 "Grand Teton / footprints 73-81 of 128")
	)
	(layers
		(0 "F.Cu" signal "TOP")
		(4 "In1.Cu" signal "GND")
		(6 "In2.Cu" signal "GND1")
		(2 "B.Cu" signal "BOTTOM")
		(9 "F.Adhes" user "F.Adhesive")
		(11 "B.Adhes" user "B.Adhesive")
		(13 "F.Paste" user "Package Geometry/Pastemask Top")
		(15 "B.Paste" user "Package Geometry/Pastemask Bottom")
		(5 "F.SilkS" user "Ref Des/Silkscreen Top")
		(7 "B.SilkS" user "Ref Des/Silkscreen Bottom")
		(1 "F.Mask" user "Board Geometry/Soldermask Top")
		(3 "B.Mask" user "Board Geometry/Soldermask Bottom")
		(17 "Dwgs.User" user "User.Drawings")
		(19 "Cmts.User" user "User.Comments")
		(21 "Eco1.User" user "User.Eco1")
		(23 "Eco2.User" user "User.Eco2")
		(25 "Edge.Cuts" user "Board Geometry/Outline")
		(27 "Margin" user)
		(31 "F.CrtYd" user "Package Geometry/Place Bound Top")
		(29 "B.CrtYd" user "Package Geometry/Place Bound Bottom")
		(35 "F.Fab" user "Ref Des/Assembly Top")
		(33 "B.Fab" user "Ref Des/Assembly Bottom")
	)
	(footprint ""
		(layer "F.Cu")
		(at 15.875 -47.117 180)
		(property "Reference" "R59"
			(at -2.54 -0.02667 0)
			(unlocked yes)
			(layer "F.SilkS")
			(effects
				(font
					(size 0.7874 0.5842)
					(thickness 0.1524)
				)
			)
		)
		(property "Value" ""
			(at 0 0 180)
			(layer "F.Fab")
			(effects
				(font
					(size 1.27 1.27)
				)
			)
		)
		(duplicate_pad_numbers_are_jumpers no)
		(fp_line
			(start 0.7874 0.4064)
			(end -0.7874 0.4064)
			(stroke
				(width 0.1524)
				(type default)
			)
			(layer "F.SilkS")
		)
		(fp_line
			(start 0.7874 -0.4064)
			(end 0.7874 0.4064)
			(stroke
				(width 0.1524)
				(type default)
			)
			(layer "F.SilkS")
		)
		(fp_line
			(start -0.7874 0.4064)
			(end -0.7874 -0.4064)
			(stroke
				(width 0.1524)
				(type default)
			)
			(layer "F.SilkS")
		)
		(fp_line
			(start -0.7874 -0.4064)
			(end 0.7874 -0.4064)
			(stroke
				(width 0.1524)
				(type default)
			)
			(layer "F.SilkS")
		)
		(fp_line
			(start 0.67945 0.3048)
			(end 0.120396 0.3048)
			(stroke
				(width 0.1)
				(type default)
			)
			(layer "F.Fab")
		)
		(fp_line
			(start 0.67945 -0.3048)
			(end 0.67945 0.3048)
			(stroke
				(width 0.1)
				(type default)
			)
			(layer "F.Fab")
		)
		(fp_line
			(start 0.12065 -0.2794)
			(end 0.12065 -0.3048)
			(stroke
				(width 0.1)
				(type default)
			)
			(layer "F.Fab")
		)
		(fp_line
			(start 0.12065 -0.3048)
			(end 0.67945 -0.3048)
			(stroke
				(width 0.1)
				(type default)
			)
			(layer "F.Fab")
		)
		(fp_line
			(start 0.120396 0.3048)
			(end 0.120396 0.2794)
			(stroke
				(width 0.1)
				(type default)
			)
			(layer "F.Fab")
		)
		(fp_line
			(start 0.120396 0.2794)
			(end -0.12065 0.2794)
			(stroke
				(width 0.1)
				(type default)
			)
			(layer "F.Fab")
		)
		(fp_line
			(start -0.12065 0.3048)
			(end -0.67945 0.3048)
			(stroke
				(width 0.1)
				(type default)
			)
			(layer "F.Fab")
		)
		(fp_line
			(start -0.12065 0.2794)
			(end -0.12065 0.3048)
			(stroke
				(width 0.1)
				(type default)
			)
			(layer "F.Fab")
		)
		(fp_line
			(start -0.12065 -0.2794)
			(end 0.12065 -0.2794)
			(stroke
				(width 0.1)
				(type default)
			)
			(layer "F.Fab")
		)
		(fp_line
			(start -0.12065 -0.305054)
			(end -0.12065 -0.2794)
			(stroke
				(width 0.1)
				(type default)
			)
			(layer "F.Fab")
		)
		(fp_line
			(start -0.67945 0.3048)
			(end -0.67945 -0.305054)
			(stroke
				(width 0.1)
				(type default)
			)
			(layer "F.Fab")
		)
		(fp_line
			(start -0.67945 -0.305054)
			(end -0.12065 -0.305054)
			(stroke
				(width 0.1)
				(type default)
			)
			(layer "F.Fab")
		)
		(pad "1" smd circle
			(at -0.40005 0 180)
			(size 0 0)
			(layers "F.Cu" "F.Mask" "F.Paste")
			(net "SMB_SCL")
		)
		(pad "2" smd circle
			(at 0.40005 0 180)
			(size 0 0)
			(layers "F.Cu" "F.Mask" "F.Paste")
			(net "SMB_FRU_SCL")
		)
	)
	(footprint ""
		(layer "F.Cu")
		(at -77.343 -64.0842 90)
		(property "Reference" "ME7"
			(at 0 0 90)
			(layer "F.SilkS")
			(hide yes)
			(effects
				(font
					(size 1.27 1.27)
				)
			)
		)
		(property "Value" ""
			(at 0 0 90)
			(layer "F.Fab")
			(effects
				(font
					(size 1.27 1.27)
				)
			)
		)
		(duplicate_pad_numbers_are_jumpers no)
	)
	(footprint ""
		(layer "F.Cu")
		(at 13.081 -24.384 90)
		(property "Reference" "Q1"
			(at -1.524 1.80467 90)
			(unlocked yes)
			(layer "F.SilkS")
			(effects
				(font
					(size 0.7874 0.5842)
					(thickness 0.1524)
				)
				(justify left)
			)
		)
		(property "Value" ""
			(at 0 0 90)
			(layer "F.Fab")
			(effects
				(font
					(size 1.27 1.27)
				)
			)
		)
		(duplicate_pad_numbers_are_jumpers no)
		(fp_line
			(start 1.38176 -1.100074)
			(end 0.592074 -1.100074)
			(stroke
				(width 0.1524)
				(type default)
			)
			(layer "F.SilkS")
		)
		(fp_line
			(start 0.592074 -1.100074)
			(end 0 -0.508)
			(stroke
				(width 0.1524)
				(type default)
			)
			(layer "F.SilkS")
		)
		(fp_line
			(start -0.592074 -1.100074)
			(end -1.38176 -1.100074)
			(stroke
				(width 0.1524)
				(type default)
			)
			(layer "F.SilkS")
		)
		(fp_line
			(start -1.38176 -1.100074)
			(end -1.38176 1.100074)
			(stroke
				(width 0.1524)
				(type default)
			)
			(layer "F.SilkS")
		)
		(fp_line
			(start 0 -0.508)
			(end -0.592074 -1.100074)
			(stroke
				(width 0.1524)
				(type default)
			)
			(layer "F.SilkS")
		)
		(fp_line
			(start 1.38176 1.100074)
			(end 1.38176 -1.100074)
			(stroke
				(width 0.1524)
				(type default)
			)
			(layer "F.SilkS")
		)
		(fp_line
			(start -1.38176 1.100074)
			(end 1.38176 1.100074)
			(stroke
				(width 0.1524)
				(type default)
			)
			(layer "F.SilkS")
		)
		(fp_poly
			(pts
				(xy -0.780796 -1.6891) (xy -1.001014 -1.24841) (xy -1.221232 -1.6891)
			)
			(stroke
				(width 0)
				(type default)
			)
			(fill yes)
			(layer "F.SilkS")
		)
		(fp_line
			(start 0.674878 -1.100074)
			(end -0.674878 -1.100074)
			(stroke
				(width 0.1)
				(type default)
			)
			(layer "F.Fab")
		)
		(fp_line
			(start -0.674878 -1.100074)
			(end -0.674878 1.100074)
			(stroke
				(width 0.1)
				(type default)
			)
			(layer "F.Fab")
		)
		(fp_line
			(start 0.674878 1.100074)
			(end 0.674878 -1.100074)
			(stroke
				(width 0.1)
				(type default)
			)
			(layer "F.Fab")
		)
		(fp_line
			(start -0.674878 1.100074)
			(end 0.674878 1.100074)
			(stroke
				(width 0.1)
				(type default)
			)
			(layer "F.Fab")
		)
		(fp_poly
			(pts
				(xy -1.9431 -0.870204) (xy -1.50241 -0.649986) (xy -1.9431 -0.429768)
			)
			(stroke
				(width 0)
				(type default)
			)
			(fill yes)
			(layer "F.Fab")
		)
		(pad "1" smd rect
			(at -0.94996 -0.649986)
			(size 0.4318 0.6096)
			(layers "F.Cu" "F.Mask" "F.Paste")
			(net "GND")
		)
		(pad "2" smd rect
			(at -0.94996 0)
			(size 0.4318 0.6096)
			(layers "F.Cu" "F.Mask" "F.Paste")
			(net "PRSNT_DBV2_USB")
		)
		(pad "3" smd rect
			(at -0.94996 0.649986)
			(size 0.4318 0.6096)
			(layers "F.Cu" "F.Mask" "F.Paste")
			(net "PRSNT_DBV2_SLIMSAS")
		)
		(pad "4" smd rect
			(at 0.94996 0.649986)
			(size 0.4318 0.6096)
			(layers "F.Cu" "F.Mask" "F.Paste")
			(net "GND")
		)
		(pad "5" smd rect
			(at 0.94996 0)
			(size 0.4318 0.6096)
			(layers "F.Cu" "F.Mask" "F.Paste")
			(net "PRSNT_DBV2_USB_N")
		)
		(pad "6" smd rect
			(at 0.94996 -0.649986)
			(size 0.4318 0.6096)
			(layers "F.Cu" "F.Mask" "F.Paste")
			(net "PRSNT_DBV2_USB_N")
		)
	)
	(footprint ""
		(layer "F.Cu")
		(at 12.954 -76.454)
		(property "Reference" ""
			(at 0 0 0)
			(layer "F.SilkS")
			(hide yes)
			(effects
				(font
					(size 1.27 1.27)
				)
			)
		)
		(property "Value" ""
			(at 0 0 0)
			(layer "F.Fab")
			(effects
				(font
					(size 1.27 1.27)
				)
			)
		)
		(duplicate_pad_numbers_are_jumpers no)
		(pad "1" smd circle
			(at 0 0)
			(size 0.9906 0.9906)
			(layers "F.Cu" "F.Mask" "F.Paste")
			(net "Net_75")
		)
		(zone
			(layer "F.Cu")
			(hatch none 0.5)
			(connect_pads
				(clearance 0)
			)
			(min_thickness 0.25)
			(keepout
				(tracks not_allowed)
				(vias allowed)
				(pads allowed)
				(copperpour not_allowed)
				(footprints allowed)
			)
			(placement
				(enabled no)
				(sheetname "")
			)
			(fill
				(thermal_gap 0.5)
				(thermal_bridge_width 0.5)
				(island_removal_mode 0)
			)
			(polygon
				(pts
					(arc
						(start 14.5796 -76.454)
						(mid 11.3284 -76.454)
						(end 14.5796 -76.454)
					)
				)
			)
		)
	)
	(footprint ""
		(layer "F.Cu")
		(at 87.613998 -23.298912)
		(property "Reference" "J4"
			(at -3.031998 1.354582 0)
			(unlocked yes)
			(layer "F.SilkS")
			(effects
				(font
					(size 0.7874 0.5842)
					(thickness 0.1524)
				)
				(justify left)
			)
		)
		(property "Value" ""
			(at 0 0 0)
			(layer "F.Fab")
			(effects
				(font
					(size 1.27 1.27)
				)
			)
		)
		(duplicate_pad_numbers_are_jumpers no)
		(fp_line
			(start -3.330702 -4.771136)
			(end 3.330702 -4.771136)
			(stroke
				(width 0.1524)
				(type default)
			)
			(layer "F.SilkS")
		)
		(fp_line
			(start 0 4.011168)
			(end -3.330702 -4.771136)
			(stroke
				(width 0.1524)
				(type default)
			)
			(layer "F.SilkS")
		)
		(fp_line
			(start 3.330702 -4.771136)
			(end 0 4.011168)
			(stroke
				(width 0.1524)
				(type default)
			)
			(layer "F.SilkS")
		)
		(fp_line
			(start -3.330702 -4.771136)
			(end 3.330702 -4.771136)
			(stroke
				(width 0.1)
				(type default)
			)
			(layer "F.Fab")
		)
		(fp_line
			(start 0 4.011168)
			(end -3.330702 -4.771136)
			(stroke
				(width 0.1)
				(type default)
			)
			(layer "F.Fab")
		)
		(fp_line
			(start 3.330702 -4.771136)
			(end 0 4.011168)
			(stroke
				(width 0.1)
				(type default)
			)
			(layer "F.Fab")
		)
		(pad "1" thru_hole circle
			(at 0 0)
			(size 2.159 2.159)
			(drill 1.7018)
			(layers "*.Cu" "*.Mask")
			(remove_unused_layers no)
			(net "GND_TDR")
			(clearance 0.0254)
			(thermal_gap 0.0254)
		)
		(pad "2" thru_hole circle
			(at -1.27 -3.348736)
			(size 2.159 2.159)
			(drill 1.7018)
			(layers "*.Cu" "*.Mask")
			(remove_unused_layers no)
			(net "TDR_SE_50_OHM_BOT")
			(clearance 0.0254)
			(thermal_gap 0.0254)
		)
		(pad "3" thru_hole circle
			(at 1.27 -3.348736)
			(size 2.159 2.159)
			(drill 1.7018)
			(layers "*.Cu" "*.Mask")
			(remove_unused_layers no)
			(net "TDR_SE_50_OHM_BOT")
			(clearance 0.0254)
			(thermal_gap 0.0254)
		)
	)
	(footprint ""
		(layer "F.Cu")
		(at 36.703 -23.368 180)
		(property "Reference" "R34"
			(at 2.032 -0.02667 0)
			(unlocked yes)
			(layer "F.SilkS")
			(effects
				(font
					(size 0.7874 0.5842)
					(thickness 0.1524)
				)
			)
		)
		(property "Value" ""
			(at 0 0 180)
			(layer "F.Fab")
			(effects
				(font
					(size 1.27 1.27)
				)
			)
		)
		(duplicate_pad_numbers_are_jumpers no)
		(fp_line
			(start 0.7874 0.4064)
			(end -0.7874 0.4064)
			(stroke
				(width 0.1524)
				(type default)
			)
			(layer "F.SilkS")
		)
		(fp_line
			(start 0.7874 -0.4064)
			(end 0.7874 0.4064)
			(stroke
				(width 0.1524)
				(type default)
			)
			(layer "F.SilkS")
		)
		(fp_line
			(start -0.7874 0.4064)
			(end -0.7874 -0.4064)
			(stroke
				(width 0.1524)
				(type default)
			)
			(layer "F.SilkS")
		)
		(fp_line
			(start -0.7874 -0.4064)
			(end 0.7874 -0.4064)
			(stroke
				(width 0.1524)
				(type default)
			)
			(layer "F.SilkS")
		)
		(fp_line
			(start 0.67945 0.3048)
			(end 0.120396 0.3048)
			(stroke
				(width 0.1)
				(type default)
			)
			(layer "F.Fab")
		)
		(fp_line
			(start 0.67945 -0.3048)
			(end 0.67945 0.3048)
			(stroke
				(width 0.1)
				(type default)
			)
			(layer "F.Fab")
		)
		(fp_line
			(start 0.12065 -0.2794)
			(end 0.12065 -0.3048)
			(stroke
				(width 0.1)
				(type default)
			)
			(layer "F.Fab")
		)
		(fp_line
			(start 0.12065 -0.3048)
			(end 0.67945 -0.3048)
			(stroke
				(width 0.1)
				(type default)
			)
			(layer "F.Fab")
		)
		(fp_line
			(start 0.120396 0.3048)
			(end 0.120396 0.2794)
			(stroke
				(width 0.1)
				(type default)
			)
			(layer "F.Fab")
		)
		(fp_line
			(start 0.120396 0.2794)
			(end -0.12065 0.2794)
			(stroke
				(width 0.1)
				(type default)
			)
			(layer "F.Fab")
		)
		(fp_line
			(start -0.12065 0.3048)
			(end -0.67945 0.3048)
			(stroke
				(width 0.1)
				(type default)
			)
			(layer "F.Fab")
		)
		(fp_line
			(start -0.12065 0.2794)
			(end -0.12065 0.3048)
			(stroke
				(width 0.1)
				(type default)
			)
			(layer "F.Fab")
		)
		(fp_line
			(start -0.12065 -0.2794)
			(end 0.12065 -0.2794)
			(stroke
				(width 0.1)
				(type default)
			)
			(layer "F.Fab")
		)
		(fp_line
			(start -0.12065 -0.305054)
			(end -0.12065 -0.2794)
			(stroke
				(width 0.1)
				(type default)
			)
			(layer "F.Fab")
		)
		(fp_line
			(start -0.67945 0.3048)
			(end -0.67945 -0.305054)
			(stroke
				(width 0.1)
				(type default)
			)
			(layer "F.Fab")
		)
		(fp_line
			(start -0.67945 -0.305054)
			(end -0.12065 -0.305054)
			(stroke
				(width 0.1)
				(type default)
			)
			(layer "F.Fab")
		)
		(pad "1" smd circle
			(at -0.40005 0 180)
			(size 0 0)
			(layers "F.Cu" "F.Mask" "F.Paste")
			(net "P3V3_STBY")
		)
		(pad "2" smd circle
			(at 0.40005 0 180)
			(size 0 0)
			(layers "F.Cu" "F.Mask" "F.Paste")
			(net "THERMAL_ADDR_A2")
		)
	)
	(footprint ""
		(layer "F.Cu")
		(at 36.703 -20.32)
		(property "Reference" "R37"
			(at -2.032 0.02667 0)
			(unlocked yes)
			(layer "F.SilkS")
			(effects
				(font
					(size 0.7874 0.5842)
					(thickness 0.1524)
				)
			)
		)
		(property "Value" ""
			(at 0 0 0)
			(layer "F.Fab")
			(effects
				(font
					(size 1.27 1.27)
				)
			)
		)
		(duplicate_pad_numbers_are_jumpers no)
		(fp_line
			(start -0.7874 -0.4064)
			(end 0.7874 -0.4064)
			(stroke
				(width 0.1524)
				(type default)
			)
			(layer "F.SilkS")
		)
		(fp_line
			(start -0.7874 0.4064)
			(end -0.7874 -0.4064)
			(stroke
				(width 0.1524)
				(type default)
			)
			(layer "F.SilkS")
		)
		(fp_line
			(start 0.7874 -0.4064)
			(end 0.7874 0.4064)
			(stroke
				(width 0.1524)
				(type default)
			)
			(layer "F.SilkS")
		)
		(fp_line
			(start 0.7874 0.4064)
			(end -0.7874 0.4064)
			(stroke
				(width 0.1524)
				(type default)
			)
			(layer "F.SilkS")
		)
		(fp_line
			(start -0.67945 -0.305054)
			(end -0.12065 -0.305054)
			(stroke
				(width 0.1)
				(type default)
			)
			(layer "F.Fab")
		)
		(fp_line
			(start -0.67945 0.3048)
			(end -0.67945 -0.305054)
			(stroke
				(width 0.1)
				(type default)
			)
			(layer "F.Fab")
		)
		(fp_line
			(start -0.12065 -0.305054)
			(end -0.12065 -0.2794)
			(stroke
				(width 0.1)
				(type default)
			)
			(layer "F.Fab")
		)
		(fp_line
			(start -0.12065 -0.2794)
			(end 0.12065 -0.2794)
			(stroke
				(width 0.1)
				(type default)
			)
			(layer "F.Fab")
		)
		(fp_line
			(start -0.12065 0.2794)
			(end -0.12065 0.3048)
			(stroke
				(width 0.1)
				(type default)
			)
			(layer "F.Fab")
		)
		(fp_line
			(start -0.12065 0.3048)
			(end -0.67945 0.3048)
			(stroke
				(width 0.1)
				(type default)
			)
			(layer "F.Fab")
		)
		(fp_line
			(start 0.120396 0.2794)
			(end -0.12065 0.2794)
			(stroke
				(width 0.1)
				(type default)
			)
			(layer "F.Fab")
		)
		(fp_line
			(start 0.120396 0.3048)
			(end 0.120396 0.2794)
			(stroke
				(width 0.1)
				(type default)
			)
			(layer "F.Fab")
		)
		(fp_line
			(start 0.12065 -0.3048)
			(end 0.67945 -0.3048)
			(stroke
				(width 0.1)
				(type default)
			)
			(layer "F.Fab")
		)
		(fp_line
			(start 0.12065 -0.2794)
			(end 0.12065 -0.3048)
			(stroke
				(width 0.1)
				(type default)
			)
			(layer "F.Fab")
		)
		(fp_line
			(start 0.67945 -0.3048)
			(end 0.67945 0.3048)
			(stroke
				(width 0.1)
				(type default)
			)
			(layer "F.Fab")
		)
		(fp_line
			(start 0.67945 0.3048)
			(end 0.120396 0.3048)
			(stroke
				(width 0.1)
				(type default)
			)
			(layer "F.Fab")
		)
		(pad "1" smd circle
			(at -0.40005 0)
			(size 0 0)
			(layers "F.Cu" "F.Mask" "F.Paste")
			(net "THERMAL_ADDR_A0")
		)
		(pad "2" smd circle
			(at 0.40005 0)
			(size 0 0)
			(layers "F.Cu" "F.Mask" "F.Paste")
			(net "GND")
		)
	)
	(footprint ""
		(layer "F.Cu")
		(at 32.385 -32.385 180)
		(property "Reference" "C15"
			(at 1.016 8.10133 0)
			(unlocked yes)
			(layer "F.SilkS")
			(effects
				(font
					(size 0.7874 0.5842)
					(thickness 0.1524)
				)
				(justify left)
			)
		)
		(property "Value" ""
			(at 0 0 180)
			(layer "F.Fab")
			(effects
				(font
					(size 1.27 1.27)
				)
			)
		)
		(duplicate_pad_numbers_are_jumpers no)
		(fp_line
			(start 1.524 0.762)
			(end -1.524 0.762)
			(stroke
				(width 0.1524)
				(type default)
			)
			(layer "F.SilkS")
		)
		(fp_line
			(start 1.524 -0.762)
			(end 1.524 0.762)
			(stroke
				(width 0.1524)
				(type default)
			)
			(layer "F.SilkS")
		)
		(fp_line
			(start -1.524 0.762)
			(end -1.524 -0.762)
			(stroke
				(width 0.1524)
				(type default)
			)
			(layer "F.SilkS")
		)
		(fp_line
			(start -1.524 -0.762)
			(end 1.524 -0.762)
			(stroke
				(width 0.1524)
				(type default)
			)
			(layer "F.SilkS")
		)
		(fp_line
			(start 1.1049 0.724916)
			(end 1.1049 -0.724916)
			(stroke
				(width 0.1)
				(type default)
			)
			(layer "F.Fab")
		)
		(fp_line
			(start 1.1049 -0.724916)
			(end -1.1049 -0.724916)
			(stroke
				(width 0.1)
				(type default)
			)
			(layer "F.Fab")
		)
		(fp_line
			(start -1.1049 0.724916)
			(end 1.1049 0.724916)
			(stroke
				(width 0.1)
				(type default)
			)
			(layer "F.Fab")
		)
		(fp_line
			(start -1.1049 -0.724916)
			(end -1.1049 0.724916)
			(stroke
				(width 0.1)
				(type default)
			)
			(layer "F.Fab")
		)
		(pad "1" smd rect
			(at -0.889 0)
			(size 1.016 1.27)
			(layers "F.Cu" "F.Mask" "F.Paste")
			(net "P5V_STBY_DEBUG")
		)
		(pad "2" smd rect
			(at 0.889 0)
			(size 1.016 1.27)
			(layers "F.Cu" "F.Mask" "F.Paste")
			(net "GND")
		)
	)
	(footprint ""
		(layer "F.Cu")
		(at 2.98196 -37.505132)
		(property "Reference" "ME6"
			(at 0 0 0)
			(layer "F.SilkS")
			(hide yes)
			(effects
				(font
					(size 1.27 1.27)
				)
			)
		)
		(property "Value" ""
			(at 0 0 0)
			(layer "F.Fab")
			(effects
				(font
					(size 1.27 1.27)
				)
			)
		)
		(duplicate_pad_numbers_are_jumpers no)
		(fp_text user "P/N"
			(at 2.3368 -3.39725 0)
			(unlocked yes)
			(layer "F.SilkS")
			(effects
				(font
					(size 1.905 1.4224)
					(thickness 0.1524)
				)
				(justify left)
			)
		)
	)
)
